FILE_TYPE = MACRO_DRAWING;
SET COLOR_WIRE YELLOW;
SET COLOR_PROP MONO;
SET COLOR_DOT WHITE;
SET COLOR_ARC YELLOW;
SET COLOR_BODY GREEN;
SET COLOR_NOTE MONO;
SET PROP_DISPLAY VALUE;
SET PAGE_NUMBER P39;
FORCEADD OFFPAGE..1
(-6400 1900);
FORCEPROP 2 LAST $XR0 97 
J 0
(-6621 1900);
DISPLAY 0.638298 (-6621 1900);
PAINT MONO (-6621 1900);
FORCEPROP 2 LAST CDS_LIB mstr_standard
J 0
(-6400 1900);
PAINT ORANGE (-6400 1900);
DISPLAY INVISIBLE (-6400 1900);
FORCEPROP 1 LAST OFFPAGE TRUE
J 0
(-6075 1775);
DISPLAY 0.872340 (-6075 1775);
PAINT GREEN (-6075 1775);
DISPLAY INVISIBLE (-6075 1775);
FORCEPROP 1 LAST COMMENT_BODY TRUE
J 0
(-6275 1800);
DISPLAY 0.872340 (-6275 1800);
PAINT GREEN (-6275 1800);
DISPLAY INVISIBLE (-6275 1800);
FORCEPROP 2 LAST PATH I122
J 0
(-6350 1975);
DISPLAY 1.021277 (-6350 1975);
PAINT ORANGE (-6350 1975);
DISPLAY INVISIBLE (-6350 1975);
FORCEADD VCC_CORE..1
(-2250 4025);
FORCEPROP 3 LASTPIN (-2250 3975) SIG_NAME PVCCMCP_CPU0\g
J 0
(-2240 3985);
DISPLAY 0.659574 (-2240 3985);
PAINT MONO (-2240 3985);
DISPLAY INVISIBLE (-2240 3985);
FORCEPROP 1 LAST HDL_POWER PVCCMCP_CPU0
J 1
(-2250 4075);
DISPLAY 0.617021 (-2250 4075);
PAINT GREEN (-2250 4075);
FORCEPROP 2 LAST CDS_LIB mstr_symbols
J 0
(-2250 4025);
PAINT ORANGE (-2250 4025);
DISPLAY INVISIBLE (-2250 4025);
FORCEPROP 1 LAST PATH I123
J 0
(-2200 4050);
DISPLAY 0.872340 (-2200 4050);
PAINT AQUA (-2200 4050);
DISPLAY INVISIBLE (-2200 4050);
FORCEADD VCC_CORE..1
(-6500 2900);
FORCEPROP 3 LASTPIN (-6500 2850) SIG_NAME PVCCMCP_CPU0\g
J 0
(-6490 2860);
DISPLAY 0.659574 (-6490 2860);
PAINT MONO (-6490 2860);
DISPLAY INVISIBLE (-6490 2860);
FORCEPROP 1 LAST HDL_POWER PVCCMCP_CPU0
J 1
(-6500 2950);
DISPLAY 0.617021 (-6500 2950);
PAINT GREEN (-6500 2950);
FORCEPROP 1 LAST PATH I125
J 0
(-6450 2925);
DISPLAY 0.872340 (-6450 2925);
PAINT AQUA (-6450 2925);
DISPLAY INVISIBLE (-6450 2925);
FORCEPROP 2 LAST CDS_LIB mstr_symbols
J 0
(-6500 2900);
PAINT ORANGE (-6500 2900);
DISPLAY INVISIBLE (-6500 2900);
FORCEADD VCC_CORE..1
(-7100 1950);
FORCEPROP 3 LASTPIN (-7100 1900) SIG_NAME PVCCMCP_CPU0\g
J 0
(-7090 1910);
DISPLAY 0.659574 (-7090 1910);
PAINT MONO (-7090 1910);
DISPLAY INVISIBLE (-7090 1910);
FORCEPROP 1 LAST HDL_POWER PVCCMCP_CPU0
J 1
(-7100 2000);
DISPLAY 0.617021 (-7100 2000);
PAINT GREEN (-7100 2000);
FORCEPROP 2 LAST CDS_LIB mstr_symbols
J 0
(-7100 1950);
PAINT ORANGE (-7100 1950);
DISPLAY INVISIBLE (-7100 1950);
FORCEPROP 1 LAST PATH I126
J 0
(-7050 1975);
DISPLAY 0.872340 (-7050 1975);
PAINT AQUA (-7050 1975);
DISPLAY INVISIBLE (-7050 1975);
FORCEADD SKX_EXT_B..22
(-4250 2550);
FORCEPROP 2 LASTPIN (-5300 2650) $PN CN22
J 2
(-5310 2660);
DISPLAY 0.617021 (-5310 2660);
PAINT ORANGE (-5310 2660);
FORCEPROP 1 LAST LOCATION U5D1
J 0
(-5250 4200);
DISPLAY 0.617021 (-5250 4200);
PAINT AQUA (-5250 4200);
FORCEPROP 1 LAST PART_NUMBER TBD
J 0
(-5250 750);
DISPLAY 0.617021 (-5250 750);
PAINT BLUE (-5250 750);
FORCEPROP 1 LAST MATERIAL IC
J 0
(-5250 4150);
DISPLAY 0.617021 (-5250 4150);
PAINT SKYBLUE (-5250 4150);
FORCEPROP 2 LASTPIN (-5300 2450) $PN CG76
J 2
(-5310 2460);
DISPLAY 0.617021 (-5310 2460);
PAINT ORANGE (-5310 2460);
FORCEPROP 2 LASTPIN (-5300 2000) $PN BF5
J 2
(-5310 2010);
DISPLAY 0.617021 (-5310 2010);
PAINT ORANGE (-5310 2010);
FORCEPROP 2 LASTPIN (-5300 2500) $PN CE76
J 2
(-5310 2510);
DISPLAY 0.617021 (-5310 2510);
PAINT ORANGE (-5310 2510);
FORCEPROP 2 LASTPIN (-5300 2050) $PN BH5
J 2
(-5310 2060);
DISPLAY 0.617021 (-5310 2060);
PAINT ORANGE (-5310 2060);
FORCEPROP 2 LASTPIN (-5300 3950) $PN CN6
J 2
(-5310 3960);
DISPLAY 0.617021 (-5310 3960);
PAINT ORANGE (-5310 3960);
FORCEPROP 2 LASTPIN (-5300 3900) $PN CU12
J 2
(-5310 3910);
DISPLAY 0.617021 (-5310 3910);
PAINT ORANGE (-5310 3910);
FORCEPROP 2 LASTPIN (-5300 3800) $PN CV21
J 2
(-5310 3810);
DISPLAY 0.617021 (-5310 3810);
PAINT ORANGE (-5310 3810);
FORCEPROP 2 LASTPIN (-5300 3750) $PN CU18
J 2
(-5310 3760);
DISPLAY 0.617021 (-5310 3760);
PAINT ORANGE (-5310 3760);
FORCEPROP 2 LASTPIN (-5300 3700) $PN CY17
J 2
(-5310 3710);
DISPLAY 0.617021 (-5310 3710);
PAINT ORANGE (-5310 3710);
FORCEPROP 2 LASTPIN (-5300 3650) $PN DC18
J 2
(-5310 3660);
DISPLAY 0.617021 (-5310 3660);
PAINT ORANGE (-5310 3660);
FORCEPROP 2 LASTPIN (-5300 3600) $PN DE14
J 2
(-5310 3610);
DISPLAY 0.617021 (-5310 3610);
PAINT ORANGE (-5310 3610);
FORCEPROP 2 LASTPIN (-5300 3500) $PN CL20
J 2
(-5310 3510);
DISPLAY 0.617021 (-5310 3510);
PAINT ORANGE (-5310 3510);
FORCEPROP 2 LASTPIN (-5300 3450) $PN CG14
J 2
(-5310 3460);
DISPLAY 0.617021 (-5310 3460);
PAINT ORANGE (-5310 3460);
FORCEPROP 2 LASTPIN (-5300 3350) $PN CF5
J 2
(-5310 3360);
DISPLAY 0.617021 (-5310 3360);
PAINT ORANGE (-5310 3360);
FORCEPROP 2 LASTPIN (-5300 3300) $PN DK21
J 2
(-5310 3310);
DISPLAY 0.617021 (-5310 3310);
PAINT ORANGE (-5310 3310);
FORCEPROP 2 LASTPIN (-5300 3250) $PN BE24
J 2
(-5310 3260);
DISPLAY 0.617021 (-5310 3260);
PAINT ORANGE (-5310 3260);
FORCEPROP 2 LASTPIN (-5300 3150) $PN AT5
J 2
(-5310 3160);
DISPLAY 0.617021 (-5310 3160);
PAINT ORANGE (-5310 3160);
FORCEPROP 2 LASTPIN (-5300 3100) $PN AM5
J 2
(-5310 3110);
DISPLAY 0.617021 (-5310 3110);
PAINT ORANGE (-5310 3110);
FORCEPROP 2 LASTPIN (-5300 3050) $PN DV11
J 2
(-5310 3060);
DISPLAY 0.617021 (-5310 3060);
PAINT ORANGE (-5310 3060);
FORCEPROP 2 LASTPIN (-5300 3000) $PN AF5
J 2
(-5310 3010);
DISPLAY 0.617021 (-5310 3010);
PAINT ORANGE (-5310 3010);
FORCEPROP 2 LASTPIN (-5300 2950) $PN AE10
J 2
(-5310 2960);
DISPLAY 0.617021 (-5310 2960);
PAINT ORANGE (-5310 2960);
FORCEPROP 2 LASTPIN (-5300 2900) $PN EE10
J 2
(-5310 2910);
DISPLAY 0.617021 (-5310 2910);
PAINT ORANGE (-5310 2910);
FORCEPROP 2 LASTPIN (-5300 2800) $PN CL26
J 2
(-5310 2810);
DISPLAY 0.617021 (-5310 2810);
PAINT ORANGE (-5310 2810);
FORCEPROP 2 LASTPIN (-5300 2750) $PN CM23
J 2
(-5310 2760);
DISPLAY 0.617021 (-5310 2760);
PAINT ORANGE (-5310 2760);
FORCEPROP 2 LASTPIN (-5300 2700) $PN CM25
J 2
(-5310 2710);
DISPLAY 0.617021 (-5310 2710);
PAINT ORANGE (-5310 2710);
FORCEPROP 2 LASTPIN (-5300 2600) $PN CN24
J 2
(-5310 2610);
DISPLAY 0.617021 (-5310 2610);
PAINT ORANGE (-5310 2610);
FORCEPROP 2 LASTPIN (-5300 1900) $PN CN28
J 2
(-5310 1910);
DISPLAY 0.617021 (-5310 1910);
PAINT ORANGE (-5310 1910);
FORCEPROP 2 LASTPIN (-5300 1850) $PN CP23
J 2
(-5310 1860);
DISPLAY 0.617021 (-5310 1860);
PAINT ORANGE (-5310 1860);
FORCEPROP 2 LASTPIN (-5300 1800) $PN CP31
J 2
(-5310 1810);
DISPLAY 0.617021 (-5310 1810);
PAINT ORANGE (-5310 1810);
FORCEPROP 2 LASTPIN (-5300 1750) $PN CR60
J 2
(-5310 1760);
DISPLAY 0.617021 (-5310 1760);
PAINT ORANGE (-5310 1760);
FORCEPROP 2 LASTPIN (-5300 1700) $PN CT23
J 2
(-5310 1710);
DISPLAY 0.617021 (-5310 1710);
PAINT ORANGE (-5310 1710);
FORCEPROP 2 LASTPIN (-5300 1650) $PN CT5
J 2
(-5310 1660);
DISPLAY 0.617021 (-5310 1660);
PAINT ORANGE (-5310 1660);
FORCEPROP 2 LASTPIN (-5300 1600) $PN CT69
J 2
(-5310 1610);
DISPLAY 0.617021 (-5310 1610);
PAINT ORANGE (-5310 1610);
FORCEPROP 2 LASTPIN (-5300 1550) $PN CU24
J 2
(-5310 1560);
DISPLAY 0.617021 (-5310 1560);
PAINT ORANGE (-5310 1560);
FORCEPROP 2 LASTPIN (-5300 1500) $PN CU6
J 2
(-5310 1510);
DISPLAY 0.617021 (-5310 1510);
PAINT ORANGE (-5310 1510);
FORCEPROP 2 LASTPIN (-5300 1450) $PN CU60
J 2
(-5310 1460);
DISPLAY 0.617021 (-5310 1460);
PAINT ORANGE (-5310 1460);
FORCEPROP 2 LASTPIN (-5300 1400) $PN CV23
J 2
(-5310 1410);
DISPLAY 0.617021 (-5310 1410);
PAINT ORANGE (-5310 1410);
FORCEPROP 2 LASTPIN (-5300 1350) $PN CV69
J 2
(-5310 1360);
DISPLAY 0.617021 (-5310 1360);
PAINT ORANGE (-5310 1360);
FORCEPROP 2 LASTPIN (-5300 1300) $PN CW22
J 2
(-5310 1310);
DISPLAY 0.617021 (-5310 1310);
PAINT ORANGE (-5310 1310);
FORCEPROP 2 LASTPIN (-5300 1250) $PN CW24
J 2
(-5310 1260);
DISPLAY 0.617021 (-5310 1260);
PAINT ORANGE (-5310 1260);
FORCEPROP 2 LASTPIN (-5300 1200) $PN CW60
J 2
(-5310 1210);
DISPLAY 0.617021 (-5310 1210);
PAINT ORANGE (-5310 1210);
FORCEPROP 2 LASTPIN (-3200 3900) $PN CY23
J 0
(-3190 3910);
DISPLAY 0.617021 (-3190 3910);
PAINT ORANGE (-3190 3910);
FORCEPROP 2 LASTPIN (-3200 3850) $PN CY25
J 0
(-3190 3860);
DISPLAY 0.617021 (-3190 3860);
PAINT ORANGE (-3190 3860);
FORCEPROP 2 LASTPIN (-3200 3800) $PN CY39
J 0
(-3190 3810);
DISPLAY 0.617021 (-3190 3810);
PAINT ORANGE (-3190 3810);
FORCEPROP 2 LASTPIN (-3200 3750) $PN CY53
J 0
(-3190 3760);
DISPLAY 0.617021 (-3190 3760);
PAINT ORANGE (-3190 3760);
FORCEPROP 2 LASTPIN (-3200 3700) $PN CY57
J 0
(-3190 3710);
DISPLAY 0.617021 (-3190 3710);
PAINT ORANGE (-3190 3710);
FORCEPROP 2 LASTPIN (-3200 3650) $PN CY63
J 0
(-3190 3660);
DISPLAY 0.617021 (-3190 3660);
PAINT ORANGE (-3190 3660);
FORCEPROP 2 LASTPIN (-3200 3600) $PN CY73
J 0
(-3190 3610);
DISPLAY 0.617021 (-3190 3610);
PAINT ORANGE (-3190 3610);
FORCEPROP 2 LASTPIN (-3200 3550) $PN DA24
J 0
(-3190 3560);
DISPLAY 0.617021 (-3190 3560);
PAINT ORANGE (-3190 3560);
FORCEPROP 2 LASTPIN (-3200 3500) $PN DA40
J 0
(-3190 3510);
DISPLAY 0.617021 (-3190 3510);
PAINT ORANGE (-3190 3510);
FORCEPROP 2 LASTPIN (-3200 3450) $PN DA52
J 0
(-3190 3460);
DISPLAY 0.617021 (-3190 3460);
PAINT ORANGE (-3190 3460);
FORCEPROP 2 LASTPIN (-3200 3400) $PN DA54
J 0
(-3190 3410);
DISPLAY 0.617021 (-3190 3410);
PAINT ORANGE (-3190 3410);
FORCEPROP 2 LASTPIN (-3200 3350) $PN DA56
J 0
(-3190 3360);
DISPLAY 0.617021 (-3190 3360);
PAINT ORANGE (-3190 3360);
FORCEPROP 2 LASTPIN (-3200 3300) $PN DC46
J 0
(-3190 3310);
DISPLAY 0.617021 (-3190 3310);
PAINT ORANGE (-3190 3310);
FORCEPROP 2 LASTPIN (-3200 3250) $PN DC52
J 0
(-3190 3260);
DISPLAY 0.617021 (-3190 3260);
PAINT ORANGE (-3190 3260);
FORCEPROP 2 LASTPIN (-3200 3200) $PN DD51
J 0
(-3190 3210);
DISPLAY 0.617021 (-3190 3210);
PAINT ORANGE (-3190 3210);
FORCEPROP 2 LASTPIN (-3200 3150) $PN DG36
J 0
(-3190 3160);
DISPLAY 0.617021 (-3190 3160);
PAINT ORANGE (-3190 3160);
FORCEPROP 2 LASTPIN (-3200 3100) $PN DG64
J 0
(-3190 3110);
DISPLAY 0.617021 (-3190 3110);
PAINT ORANGE (-3190 3110);
FORCEPROP 2 LASTPIN (-3200 3050) $PN DH65
J 0
(-3190 3060);
DISPLAY 0.617021 (-3190 3060);
PAINT ORANGE (-3190 3060);
FORCEPROP 2 LASTPIN (-3200 3000) $PN DJ36
J 0
(-3190 3010);
DISPLAY 0.617021 (-3190 3010);
PAINT ORANGE (-3190 3010);
FORCEPROP 2 LASTPIN (-3200 2950) $PN DJ66
J 0
(-3190 2960);
DISPLAY 0.617021 (-3190 2960);
PAINT ORANGE (-3190 2960);
FORCEPROP 2 LASTPIN (-3200 2900) $PN DK15
J 0
(-3190 2910);
DISPLAY 0.617021 (-3190 2910);
PAINT ORANGE (-3190 2910);
FORCEPROP 2 LASTPIN (-3200 2850) $PN DK37
J 0
(-3190 2860);
DISPLAY 0.617021 (-3190 2860);
PAINT ORANGE (-3190 2860);
FORCEPROP 2 LASTPIN (-3200 2800) $PN DK65
J 0
(-3190 2810);
DISPLAY 0.617021 (-3190 2810);
PAINT ORANGE (-3190 2810);
FORCEPROP 2 LASTPIN (-3200 2750) $PN DK67
J 0
(-3190 2760);
DISPLAY 0.617021 (-3190 2760);
PAINT ORANGE (-3190 2760);
FORCEPROP 2 LASTPIN (-3200 2700) $PN DL38
J 0
(-3190 2710);
DISPLAY 0.617021 (-3190 2710);
PAINT ORANGE (-3190 2710);
FORCEPROP 2 LASTPIN (-3200 2650) $PN DL66
J 0
(-3190 2660);
DISPLAY 0.617021 (-3190 2660);
PAINT ORANGE (-3190 2660);
FORCEPROP 2 LASTPIN (-3200 2600) $PN DM67
J 0
(-3190 2610);
DISPLAY 0.617021 (-3190 2610);
PAINT ORANGE (-3190 2610);
FORCEPROP 2 LASTPIN (-3200 2550) $PN DN62
J 0
(-3190 2560);
DISPLAY 0.617021 (-3190 2560);
PAINT ORANGE (-3190 2560);
FORCEPROP 2 LASTPIN (-3200 2500) $PN DN66
J 0
(-3190 2510);
DISPLAY 0.617021 (-3190 2510);
PAINT ORANGE (-3190 2510);
FORCEPROP 2 LASTPIN (-3200 2450) $PN DP17
J 0
(-3190 2460);
DISPLAY 0.617021 (-3190 2460);
PAINT ORANGE (-3190 2460);
FORCEPROP 2 LASTPIN (-3200 2400) $PN DP65
J 0
(-3190 2410);
DISPLAY 0.617021 (-3190 2410);
PAINT ORANGE (-3190 2410);
FORCEPROP 2 LASTPIN (-3200 2350) $PN DR44
J 0
(-3190 2360);
DISPLAY 0.617021 (-3190 2360);
PAINT ORANGE (-3190 2360);
FORCEPROP 2 LASTPIN (-3200 2300) $PN DT71
J 0
(-3190 2310);
DISPLAY 0.617021 (-3190 2310);
PAINT ORANGE (-3190 2310);
FORCEPROP 2 LASTPIN (-3200 2200) $PN DV61
J 0
(-3190 2210);
DISPLAY 0.617021 (-3190 2210);
PAINT ORANGE (-3190 2210);
FORCEPROP 2 LASTPIN (-3200 2150) $PN DV71
J 0
(-3190 2160);
DISPLAY 0.617021 (-3190 2160);
PAINT ORANGE (-3190 2160);
FORCEPROP 2 LASTPIN (-3200 2100) $PN DW44
J 0
(-3190 2110);
DISPLAY 0.617021 (-3190 2110);
PAINT ORANGE (-3190 2110);
FORCEPROP 2 LASTPIN (-3200 2050) $PN DW46
J 0
(-3190 2060);
DISPLAY 0.617021 (-3190 2060);
PAINT ORANGE (-3190 2060);
FORCEPROP 2 LASTPIN (-3200 2000) $PN DY3
J 0
(-3190 2010);
DISPLAY 0.617021 (-3190 2010);
PAINT ORANGE (-3190 2010);
FORCEPROP 2 LASTPIN (-3200 1950) $PN EA4
J 0
(-3190 1960);
DISPLAY 0.617021 (-3190 1960);
PAINT ORANGE (-3190 1960);
FORCEPROP 2 LASTPIN (-3200 1900) $PN EA44
J 0
(-3190 1910);
DISPLAY 0.617021 (-3190 1910);
PAINT ORANGE (-3190 1910);
FORCEPROP 2 LASTPIN (-3200 1850) $PN EB3
J 0
(-3190 1860);
DISPLAY 0.617021 (-3190 1860);
PAINT ORANGE (-3190 1860);
FORCEPROP 2 LASTPIN (-3200 1800) $PN EB5
J 0
(-3190 1810);
DISPLAY 0.617021 (-3190 1810);
PAINT ORANGE (-3190 1810);
FORCEPROP 2 LASTPIN (-3200 1750) $PN EB85
J 0
(-3190 1760);
DISPLAY 0.617021 (-3190 1760);
PAINT ORANGE (-3190 1760);
FORCEPROP 2 LASTPIN (-3200 1700) $PN EC16
J 0
(-3190 1710);
DISPLAY 0.617021 (-3190 1710);
PAINT ORANGE (-3190 1710);
FORCEPROP 2 LASTPIN (-3200 1650) $PN EC4
J 0
(-3190 1660);
DISPLAY 0.617021 (-3190 1660);
PAINT ORANGE (-3190 1660);
FORCEPROP 2 LASTPIN (-3200 1600) $PN EC44
J 0
(-3190 1610);
DISPLAY 0.617021 (-3190 1610);
PAINT ORANGE (-3190 1610);
FORCEPROP 2 LASTPIN (-3200 1550) $PN EC84
J 0
(-3190 1560);
DISPLAY 0.617021 (-3190 1560);
PAINT ORANGE (-3190 1560);
FORCEPROP 2 LASTPIN (-3200 1500) $PN ED45
J 0
(-3190 1510);
DISPLAY 0.617021 (-3190 1510);
PAINT ORANGE (-3190 1510);
FORCEPROP 2 LASTPIN (-3200 1450) $PN ED5
J 0
(-3190 1460);
DISPLAY 0.617021 (-3190 1460);
PAINT ORANGE (-3190 1460);
FORCEPROP 2 LASTPIN (-3200 1400) $PN ED83
J 0
(-3190 1410);
DISPLAY 0.617021 (-3190 1410);
PAINT ORANGE (-3190 1410);
FORCEPROP 2 LASTPIN (-3200 1300) $PN EE46
J 0
(-3190 1310);
DISPLAY 0.617021 (-3190 1310);
PAINT ORANGE (-3190 1310);
FORCEPROP 2 LASTPIN (-3200 1250) $PN EE6
J 0
(-3190 1260);
DISPLAY 0.617021 (-3190 1260);
PAINT ORANGE (-3190 1260);
FORCEPROP 2 LASTPIN (-3200 1200) $PN EE82
J 0
(-3190 1210);
DISPLAY 0.617021 (-3190 1210);
PAINT ORANGE (-3190 1210);
FORCEPROP 2 LASTPIN (-3200 1150) $PN EE84
J 0
(-3190 1160);
DISPLAY 0.617021 (-3190 1160);
PAINT ORANGE (-3190 1160);
FORCEPROP 2 LASTPIN (-3200 1100) $PN EF47
J 0
(-3190 1110);
DISPLAY 0.617021 (-3190 1110);
PAINT ORANGE (-3190 1110);
FORCEPROP 2 LASTPIN (-3200 1050) $PN EF77
J 0
(-3190 1060);
DISPLAY 0.617021 (-3190 1060);
PAINT ORANGE (-3190 1060);
FORCEPROP 2 LASTPIN (-3200 1000) $PN EF81
J 0
(-3190 1010);
DISPLAY 0.617021 (-3190 1010);
PAINT ORANGE (-3190 1010);
FORCEPROP 2 LASTPIN (-3200 950) $PN EF83
J 0
(-3190 960);
DISPLAY 0.617021 (-3190 960);
PAINT ORANGE (-3190 960);
FORCEPROP 2 LASTPIN (-5300 2200) $PN BT17
J 2
(-5310 2210);
DISPLAY 0.617021 (-5310 2210);
PAINT ORANGE (-5310 2210);
FORCEPROP 2 LASTPIN (-5300 2150) $PN BU16
J 2
(-5310 2160);
DISPLAY 0.617021 (-5310 2160);
PAINT ORANGE (-5310 2160);
FORCEPROP 2 LASTPIN (-5300 2350) $PN BN16
J 2
(-5310 2360);
DISPLAY 0.617021 (-5310 2360);
PAINT ORANGE (-5310 2360);
FORCEPROP 2 LASTPIN (-3200 1350) $PN EE16
J 0
(-3190 1360);
DISPLAY 0.617021 (-3190 1360);
PAINT ORANGE (-3190 1360);
FORCEPROP 2 LASTPIN (-3200 2250) $PN DU44
J 0
(-3190 2260);
DISPLAY 0.617021 (-3190 2260);
PAINT ORANGE (-3190 2260);
FORCEPROP 2 LASTPIN (-5300 2300) $PN BL16
J 2
(-5310 2310);
DISPLAY 0.617021 (-5310 2310);
PAINT ORANGE (-5310 2310);
FORCEPROP 2 LASTPIN (-3200 3950) $PN CW62
J 0
(-3190 3960);
DISPLAY 0.617021 (-3190 3960);
PAINT ORANGE (-3190 3960);
FORCEPROP 2 LASTPIN (-5300 3200) $PN AT7
J 2
(-5310 3210);
DISPLAY 0.617021 (-5310 3210);
PAINT ORANGE (-5310 3210);
FORCEPROP 2 LASTPIN (-5300 3550) $PN CP13
J 2
(-5310 3560);
DISPLAY 0.617021 (-5310 3560);
PAINT ORANGE (-5310 3560);
FORCEPROP 1 LAST PACK_TYPE BGA1
J 0
(-5250 4250);
PAINT SKYBLUE (-5250 4250);
DISPLAY INVISIBLE (-5250 4250);
FORCEPROP 2 LAST SEC_TYPE BGA1
J 0
(-5250 4250);
DISPLAY 1.021277 (-5250 4250);
PAINT ORANGE (-5250 4250);
DISPLAY INVISIBLE (-5250 4250);
FORCEPROP 2 LAST CDS_LIB chpset_lib
J 0
(-4250 2550);
PAINT ORANGE (-4250 2550);
DISPLAY INVISIBLE (-4250 2550);
FORCEPROP 2 LAST SEC 22
J 0
(-5250 4250);
DISPLAY 0.680851 (-5250 4250);
PAINT MONO (-5250 4250);
DISPLAY INVISIBLE (-5250 4250);
FORCEPROP 2 LAST CDS_LOCATION U5D1
J 0
(-5250 4200);
DISPLAY 0.617021 (-5250 4200);
PAINT AQUA (-5250 4200);
DISPLAY INVISIBLE (-5250 4200);
FORCEPROP 1 LAST PATH I127
J 0
(-4250 4150);
PAINT GREEN (-4250 4150);
DISPLAY INVISIBLE (-4250 4150);
FORCEPROP 0 LAST ROOM CPU0
J 0
(-5250 4300);
DISPLAY 1.021277 (-5250 4300);
PAINT ORANGE (-5250 4300);
DISPLAY INVISIBLE (-5250 4300);
FORCEADD PVCCIO_CPU0..1
(-5650 4175);
FORCEPROP 3 LASTPIN (-5650 4125) SIG_NAME PVCCIO_CPU0\g
J 0
(-5640 4135);
DISPLAY 0.659574 (-5640 4135);
PAINT MONO (-5640 4135);
DISPLAY INVISIBLE (-5640 4135);
FORCEPROP 1 LAST VOLTAGE 1.1V
J 0
(-5695 4132);
DISPLAY 0.340426 (-5695 4132);
PAINT SKYBLUE (-5695 4132);
DISPLAY INVISIBLE (-5695 4132);
FORCEPROP 2 LAST CDS_LIB mstr_symbols
J 0
(-5650 4175);
PAINT ORANGE (-5650 4175);
DISPLAY INVISIBLE (-5650 4175);
FORCEPROP 1 LAST BODY_TYPE PLUMBING
J 0
(-5695 4132);
DISPLAY 0.340426 (-5695 4132);
PAINT GREEN (-5695 4132);
DISPLAY INVISIBLE (-5695 4132);
FORCEPROP 1 LAST PATH I23
J 0
(-5600 4200);
DISPLAY 0.872340 (-5600 4200);
PAINT AQUA (-5600 4200);
DISPLAY INVISIBLE (-5600 4200);
FORCEPROP 1 LAST HDL_POWER PVCCIO_CPU0
J 1
(-5650 4225);
DISPLAY 0.872340 (-5650 4225);
PAINT GREEN (-5650 4225);
DISPLAY INVISIBLE (-5650 4225);
FORCEADD OFFPAGE..5
(-6400 2500);
FORCEPROP 2 LAST $XR0 205 
J 0
(-6685 2500);
DISPLAY 0.638298 (-6685 2500);
PAINT MONO (-6685 2500);
FORCEPROP 2 LAST CDS_LIB mstr_standard
J 0
(-6400 2500);
DISPLAY 0.489362 (-6400 2500);
PAINT ORANGE (-6400 2500);
DISPLAY INVISIBLE (-6400 2500);
FORCEPROP 1 LAST OFFPAGE TRUE
J 0
(-6075 2375);
PAINT GREEN (-6075 2375);
DISPLAY INVISIBLE (-6075 2375);
FORCEPROP 1 LAST COMMENT_BODY TRUE
J 0
(-6300 2425);
DISPLAY 0.680851 (-6300 2425);
PAINT PEACH (-6300 2425);
DISPLAY INVISIBLE (-6300 2425);
FORCEPROP 2 LAST PATH I33
J 0
(-6675 2550);
DISPLAY 1.021277 (-6675 2550);
PAINT ORANGE (-6675 2550);
DISPLAY INVISIBLE (-6675 2550);
FORCEADD OFFPAGE..5
(-6400 2450);
FORCEPROP 2 LAST $XR0 205 
J 0
(-6685 2450);
DISPLAY 0.638298 (-6685 2450);
PAINT MONO (-6685 2450);
FORCEPROP 2 LAST CDS_LIB mstr_standard
J 0
(-6400 2450);
DISPLAY 0.489362 (-6400 2450);
PAINT ORANGE (-6400 2450);
DISPLAY INVISIBLE (-6400 2450);
FORCEPROP 1 LAST OFFPAGE TRUE
J 0
(-6075 2325);
PAINT GREEN (-6075 2325);
DISPLAY INVISIBLE (-6075 2325);
FORCEPROP 1 LAST COMMENT_BODY TRUE
J 0
(-6300 2375);
DISPLAY 0.680851 (-6300 2375);
PAINT PEACH (-6300 2375);
DISPLAY INVISIBLE (-6300 2375);
FORCEPROP 2 LAST PATH I34
J 0
(-6675 2500);
DISPLAY 1.021277 (-6675 2500);
PAINT ORANGE (-6675 2500);
DISPLAY INVISIBLE (-6675 2500);
FORCEADD OFFPAGE..5
(-6400 2350);
FORCEPROP 2 LAST $XR0 194 
J 0
(-6685 2350);
DISPLAY 0.638298 (-6685 2350);
PAINT MONO (-6685 2350);
FORCEPROP 2 LAST CDS_LIB mstr_standard
J 0
(-6400 2350);
DISPLAY 0.489362 (-6400 2350);
PAINT ORANGE (-6400 2350);
DISPLAY INVISIBLE (-6400 2350);
FORCEPROP 1 LAST OFFPAGE TRUE
J 0
(-6075 2225);
PAINT GREEN (-6075 2225);
DISPLAY INVISIBLE (-6075 2225);
FORCEPROP 1 LAST COMMENT_BODY TRUE
J 0
(-6300 2275);
DISPLAY 0.680851 (-6300 2275);
PAINT PEACH (-6300 2275);
DISPLAY INVISIBLE (-6300 2275);
FORCEPROP 2 LAST PATH I35
J 0
(-6675 2400);
DISPLAY 1.021277 (-6675 2400);
PAINT ORANGE (-6675 2400);
DISPLAY INVISIBLE (-6675 2400);
FORCEADD OFFPAGE..5
(-6400 2300);
FORCEPROP 2 LAST $XR0 194 
J 0
(-6685 2300);
DISPLAY 0.638298 (-6685 2300);
PAINT MONO (-6685 2300);
FORCEPROP 2 LAST CDS_LIB mstr_standard
J 0
(-6400 2300);
DISPLAY 0.489362 (-6400 2300);
PAINT ORANGE (-6400 2300);
DISPLAY INVISIBLE (-6400 2300);
FORCEPROP 1 LAST OFFPAGE TRUE
J 0
(-6075 2175);
PAINT GREEN (-6075 2175);
DISPLAY INVISIBLE (-6075 2175);
FORCEPROP 1 LAST COMMENT_BODY TRUE
J 0
(-6300 2225);
DISPLAY 0.680851 (-6300 2225);
PAINT PEACH (-6300 2225);
DISPLAY INVISIBLE (-6300 2225);
FORCEPROP 2 LAST PATH I36
J 0
(-6675 2350);
DISPLAY 1.021277 (-6675 2350);
PAINT ORANGE (-6675 2350);
DISPLAY INVISIBLE (-6675 2350);
FORCEADD OFFPAGE..5
(-6400 2200);
FORCEPROP 2 LAST $XR0 194 
J 0
(-6685 2200);
DISPLAY 0.638298 (-6685 2200);
PAINT MONO (-6685 2200);
FORCEPROP 2 LAST CDS_LIB mstr_standard
J 0
(-6400 2200);
DISPLAY 0.489362 (-6400 2200);
PAINT ORANGE (-6400 2200);
DISPLAY INVISIBLE (-6400 2200);
FORCEPROP 1 LAST OFFPAGE TRUE
J 0
(-6075 2075);
PAINT GREEN (-6075 2075);
DISPLAY INVISIBLE (-6075 2075);
FORCEPROP 1 LAST COMMENT_BODY TRUE
J 0
(-6300 2125);
DISPLAY 0.680851 (-6300 2125);
PAINT PEACH (-6300 2125);
DISPLAY INVISIBLE (-6300 2125);
FORCEPROP 2 LAST PATH I37
J 0
(-6675 2250);
DISPLAY 1.021277 (-6675 2250);
PAINT ORANGE (-6675 2250);
DISPLAY INVISIBLE (-6675 2250);
FORCEADD OFFPAGE..5
(-6400 2150);
FORCEPROP 2 LAST $XR0 194 
J 0
(-6685 2150);
DISPLAY 0.638298 (-6685 2150);
PAINT MONO (-6685 2150);
FORCEPROP 2 LAST CDS_LIB mstr_standard
J 0
(-6400 2150);
DISPLAY 0.489362 (-6400 2150);
PAINT ORANGE (-6400 2150);
DISPLAY INVISIBLE (-6400 2150);
FORCEPROP 1 LAST OFFPAGE TRUE
J 0
(-6075 2025);
PAINT GREEN (-6075 2025);
DISPLAY INVISIBLE (-6075 2025);
FORCEPROP 1 LAST COMMENT_BODY TRUE
J 0
(-6300 2075);
DISPLAY 0.680851 (-6300 2075);
PAINT PEACH (-6300 2075);
DISPLAY INVISIBLE (-6300 2075);
FORCEPROP 2 LAST PATH I38
J 0
(-6675 2200);
DISPLAY 1.021277 (-6675 2200);
PAINT ORANGE (-6675 2200);
DISPLAY INVISIBLE (-6675 2200);
FORCEADD OFFPAGE..5
(-6400 2050);
FORCEPROP 2 LAST $XR0 212 
J 0
(-6685 2050);
DISPLAY 0.638298 (-6685 2050);
PAINT MONO (-6685 2050);
FORCEPROP 2 LAST PATH I39
J 0
(-6675 2100);
DISPLAY 1.021277 (-6675 2100);
PAINT ORANGE (-6675 2100);
DISPLAY INVISIBLE (-6675 2100);
FORCEPROP 1 LAST COMMENT_BODY TRUE
J 0
(-6300 1975);
DISPLAY 0.680851 (-6300 1975);
PAINT PEACH (-6300 1975);
DISPLAY INVISIBLE (-6300 1975);
FORCEPROP 1 LAST OFFPAGE TRUE
J 0
(-6075 1925);
PAINT GREEN (-6075 1925);
DISPLAY INVISIBLE (-6075 1925);
FORCEPROP 2 LAST CDS_LIB mstr_standard
J 0
(-6400 2050);
DISPLAY 0.489362 (-6400 2050);
PAINT ORANGE (-6400 2050);
DISPLAY INVISIBLE (-6400 2050);
FORCEADD OFFPAGE..5
(-6400 2000);
FORCEPROP 2 LAST $XR0 212 
J 0
(-6685 2000);
DISPLAY 0.638298 (-6685 2000);
PAINT MONO (-6685 2000);
FORCEPROP 2 LAST PATH I40
J 0
(-6675 2050);
DISPLAY 1.021277 (-6675 2050);
PAINT ORANGE (-6675 2050);
DISPLAY INVISIBLE (-6675 2050);
FORCEPROP 1 LAST COMMENT_BODY TRUE
J 0
(-6300 1925);
DISPLAY 0.680851 (-6300 1925);
PAINT PEACH (-6300 1925);
DISPLAY INVISIBLE (-6300 1925);
FORCEPROP 1 LAST OFFPAGE TRUE
J 0
(-6075 1875);
PAINT GREEN (-6075 1875);
DISPLAY INVISIBLE (-6075 1875);
FORCEPROP 2 LAST CDS_LIB mstr_standard
J 0
(-6400 2000);
DISPLAY 0.489362 (-6400 2000);
PAINT ORANGE (-6400 2000);
DISPLAY INVISIBLE (-6400 2000);
FORCEADD INTEL_CORP_BPAGE..1
(0 0);
FORCEPROP 1 LAST CDS_CON_LAST_MODIFIED Fri Jun 16 17:48:14 2017
J 0
(-1425 325);
DISPLAY 1.340426 (-1425 325);
PAINT GREEN (-1425 325);
DISPLAY INVISIBLE (-1425 325);
FORCEPROP 1 LAST CUSTOM_TXT_CDS <CURRENT_DESIGN_SHEET> OF <TOTAL_DESIGN_SHEETS>
J 0
(-500 25);
PAINT ORANGE (-500 25);
FORCEPROP 1 LAST CUSTOM_TXT_CDS <CON_LAST_MODIFIED>
J 0
(-4000 100);
PAINT ORANGE (-4000 100);
FORCEPROP 2 LAST CUSTOM_TXT_CDS <XR_PAGE_TITLE>
J 0
(-7890 5250);
DISPLAY 0.638298 (-7890 5250);
PAINT PINK (-7890 5250);
DISPLAY INVISIBLE (-7890 5250);
FORCEPROP 1 LAST SCH_TITLE SKYLAKE - SKT0 - 19 OF 21
J 0
(-7950 50);
DISPLAY 1.212766 (-7950 50);
PAINT GREEN (-7950 50);
FORCEPROP 2 LAST CDS_LIB mstr_symbols
J 0
(0 0);
PAINT ORANGE (0 0);
DISPLAY INVISIBLE (0 0);
FORCEPROP 2 LAST PAGE_BORDER TRUE
J 0
(-7890 5250);
DISPLAY 0.851064 (-7890 5250);
PAINT PINK (-7890 5250);
DISPLAY INVISIBLE (-7890 5250);
FORCEPROP 1 LAST COMMENT_BODY TRUE
J 0
(12 12);
DISPLAY 0.638298 (12 12);
PAINT GREEN (12 12);
DISPLAY INVISIBLE (12 12);
FORCEPROP 2 LAST CDS_XR_PAGE_TITLE CR-39 : @BASEBOARD_FAB2_LIB.BASEBOARD_FAB2(SCH_1):PAGE39
J 0
(-7890 5250);
DISPLAY 0.638298 (-7890 5250);
PAINT PINK (-7890 5250);
DISPLAY INVISIBLE (-7890 5250);
FORCEADD PRELIM..10
(-4290 3340);
PAINT GRAY (-4290 3340);
FORCEPROP 2 LAST CDS_LIB mstr_misc
J 0
(-4290 3340);
DISPLAY 0.489362 (-4290 3340);
PAINT ORANGE (-4290 3340);
DISPLAY INVISIBLE (-4290 3340);
FORCEPROP 1 LAST COMMENT_BODY TRUE
J 0
(-4290 3340);
DISPLAY 0.489362 (-4290 3340);
PAINT PEACH (-4290 3340);
DISPLAY INVISIBLE (-4290 3340);
FORCEADD DESIGN_NOTE..1
(-5000 650);
FORCEPROP 0 LAST L1 CPU SYMBOLS 1-30 ARE PRELIMINARY AND SUBJECT TO CHANGE
J 0
(-5200 525);
DISPLAY 1.021277 (-5200 525);
PAINT ORANGE (-5200 525);
FORCEPROP 2 LAST CDS_LIB mstr_symbols
J 0
(-5000 650);
PAINT ORANGE (-5000 650);
DISPLAY INVISIBLE (-5000 650);
FORCEPROP 1 LAST COMMENT_BODY TRUE
J 0
(-4975 750);
DISPLAY 0.978723 (-4975 750);
PAINT ORANGE (-4975 750);
DISPLAY INVISIBLE (-4975 750);
WIRE 16 -1 (-2250 3850)(-2250 3975);
WIRE 16 -1 (-2250 3550)(-2250 3850);
WIRE 16 -1 (-3200 3850)(-2250 3850);
WIRE 16 -1 (-3200 3550)(-2250 3550);
WIRE 16 -1 (-6500 2850)(-6500 2600);
WIRE 16 -1 (-6500 2600)(-5475 2600);
WIRE 16 -1 (-5475 2700)(-5475 2600);
WIRE 16 -1 (-5475 2600)(-5300 2600);
WIRE 16 -1 (-5475 2750)(-5475 2700);
WIRE 16 -1 (-5475 2700)(-5300 2700);
WIRE 16 -1 (-5475 2750)(-5475 2800);
WIRE 16 -1 (-5300 2750)(-5475 2750);
WIRE 16 -1 (-5475 2800)(-5300 2800);
WIRE 16 -1 (-7100 1850)(-7100 1900);
WIRE 16 -1 (-5475 1850)(-7100 1850);
WIRE 16 -1 (-5475 1700)(-5475 1850);
WIRE 16 -1 (-5300 1850)(-5475 1850);
WIRE 16 -1 (-5475 1550)(-5475 1700);
WIRE 16 -1 (-5475 1700)(-5300 1700);
WIRE 16 -1 (-5475 1400)(-5475 1550);
WIRE 16 -1 (-5475 1550)(-5300 1550);
WIRE 16 -1 (-5475 1400)(-5475 1250);
WIRE 16 -1 (-5475 1400)(-5300 1400);
WIRE 16 -1 (-5300 1250)(-5475 1250);
WIRE 16 -1 (-5650 3950)(-5650 4125);
WIRE 16 -1 (-5650 3900)(-5650 3950);
WIRE 16 -1 (-5650 3950)(-5300 3950);
WIRE 16 -1 (-5650 3800)(-5650 3900);
WIRE 16 -1 (-5650 3900)(-5300 3900);
WIRE 16 -1 (-5650 3750)(-5650 3800);
WIRE 16 -1 (-5650 3800)(-5300 3800);
WIRE 16 -1 (-5650 3700)(-5650 3750);
WIRE 16 -1 (-5650 3750)(-5300 3750);
WIRE 16 -1 (-5650 3700)(-5650 3650);
WIRE 16 -1 (-5650 3700)(-5300 3700);
WIRE 16 -1 (-5650 3650)(-5650 3600);
WIRE 16 -1 (-5650 3650)(-5300 3650);
WIRE 16 -1 (-5650 3600)(-5650 3550);
WIRE 16 -1 (-5650 3600)(-5300 3600);
WIRE 16 -1 (-5650 3550)(-5650 3500);
WIRE 16 -1 (-5650 3550)(-5300 3550);
WIRE 16 -1 (-5650 3500)(-5650 3450);
WIRE 16 -1 (-5650 3500)(-5300 3500);
WIRE 16 -1 (-5650 3350)(-5650 3450);
WIRE 16 -1 (-5650 3450)(-5300 3450);
WIRE 16 -1 (-5650 3350)(-5650 3300);
WIRE 16 -1 (-5650 3350)(-5300 3350);
WIRE 16 -1 (-5650 3300)(-5650 3250);
WIRE 16 -1 (-5650 3300)(-5300 3300);
WIRE 16 -1 (-5650 3250)(-5650 3200);
WIRE 16 -1 (-5650 3250)(-5300 3250);
WIRE 16 -1 (-5650 3200)(-5650 3150);
WIRE 16 -1 (-5650 3200)(-5300 3200);
WIRE 16 -1 (-5650 3150)(-5650 3100);
WIRE 16 -1 (-5650 3150)(-5300 3150);
WIRE 16 -1 (-5650 3100)(-5650 3050);
WIRE 16 -1 (-5650 3100)(-5300 3100);
WIRE 16 -1 (-5650 3050)(-5650 3000);
WIRE 16 -1 (-5650 3050)(-5300 3050);
WIRE 16 -1 (-5650 3000)(-5650 2950);
WIRE 16 -1 (-5650 3000)(-5300 3000);
WIRE 16 -1 (-5650 2950)(-5650 2900);
WIRE 16 -1 (-5650 2950)(-5300 2950);
WIRE 16 -1 (-5650 2900)(-5300 2900);
WIRE 16 -1 (-3200 1550)(-2525 1550);
FORCEPROP 0 LAST SIG_NAME TP_CPU0_RSVD_12
J 0
(-2935 1560);
DISPLAY 0.617021 (-2935 1560);
PAINT ORANGE (-2935 1560);
FORCEPROP 2 LASTPROP $XRERR UNIQUE?
J 0
(-2495 1550);
DISPLAY 0.638298 (-2495 1550);
PAINT MONO (-2495 1550);
DISPLAY INVISIBLE (-2495 1550);
WIRE 16 -1 (-6350 2000)(-5300 2000);
FORCEPROP 2 LAST SIG_NAME VSENSE_PVCCIO_CPU0_SKT_VRTN
J 0
(-6285 2010);
DISPLAY 0.617021 (-6285 2010);
PAINT ORANGE (-6285 2010);
WIRE 16 -1 (-5300 2050)(-6350 2050);
FORCEPROP 2 LAST SIG_NAME VSENSE_PVCCIO_CPU0_SKT_VSEN
J 0
(-6285 2060);
DISPLAY 0.617021 (-6285 2060);
PAINT ORANGE (-6285 2060);
WIRE 16 -1 (-5300 1900)(-6350 1900);
FORCEPROP 0 LAST SIG_NAME PD_CPU0_MCP01_DMON
J 0
(-6285 1910);
DISPLAY 0.617021 (-6285 1910);
PAINT ORANGE (-6285 1910);
WIRE 16 -1 (-3200 2550)(-2525 2550);
FORCEPROP 0 LAST SIG_NAME TP_CPU0_RSVD_32
J 0
(-2935 2560);
DISPLAY 0.617021 (-2935 2560);
PAINT ORANGE (-2935 2560);
FORCEPROP 2 LASTPROP $XRERR UNIQUE?
J 0
(-2495 2550);
DISPLAY 0.638298 (-2495 2550);
PAINT MONO (-2495 2550);
DISPLAY INVISIBLE (-2495 2550);
WIRE 16 -1 (-3200 2600)(-2525 2600);
FORCEPROP 0 LAST SIG_NAME TP_CPU0_RSVD_33
J 0
(-2935 2610);
DISPLAY 0.617021 (-2935 2610);
PAINT ORANGE (-2935 2610);
FORCEPROP 2 LASTPROP $XRERR UNIQUE?
J 0
(-2495 2600);
DISPLAY 0.638298 (-2495 2600);
PAINT MONO (-2495 2600);
DISPLAY INVISIBLE (-2495 2600);
WIRE 16 -1 (-3200 2650)(-2525 2650);
FORCEPROP 0 LAST SIG_NAME TP_CPU0_RSVD_34
J 0
(-2935 2660);
DISPLAY 0.617021 (-2935 2660);
PAINT ORANGE (-2935 2660);
FORCEPROP 2 LASTPROP $XRERR UNIQUE?
J 0
(-2495 2650);
DISPLAY 0.638298 (-2495 2650);
PAINT MONO (-2495 2650);
DISPLAY INVISIBLE (-2495 2650);
WIRE 16 -1 (-5300 1200)(-6350 1200);
FORCEPROP 0 LAST SIG_NAME TP_CPU0_RSVD_61
J 0
(-6285 1210);
DISPLAY 0.617021 (-6285 1210);
PAINT ORANGE (-6285 1210);
FORCEPROP 2 LASTPROP $XRERR UNIQUE?
J 0
(-6590 1200);
DISPLAY 0.638298 (-6590 1200);
PAINT MONO (-6590 1200);
DISPLAY INVISIBLE (-6590 1200);
WIRE 16 -1 (-5300 1300)(-6350 1300);
FORCEPROP 0 LAST SIG_NAME TP_CPU0_KTI2_DFX_DN
J 0
(-6285 1310);
DISPLAY 0.617021 (-6285 1310);
PAINT ORANGE (-6285 1310);
FORCEPROP 2 LASTPROP $XRERR UNIQUE?
J 0
(-6590 1300);
DISPLAY 0.638298 (-6590 1300);
PAINT MONO (-6590 1300);
DISPLAY INVISIBLE (-6590 1300);
WIRE 16 -1 (-5300 1350)(-6350 1350);
FORCEPROP 0 LAST SIG_NAME TP_CPU0_RSVD_64
J 0
(-6285 1360);
DISPLAY 0.617021 (-6285 1360);
PAINT ORANGE (-6285 1360);
FORCEPROP 2 LASTPROP $XRERR UNIQUE?
J 0
(-6590 1350);
DISPLAY 0.638298 (-6590 1350);
PAINT MONO (-6590 1350);
DISPLAY INVISIBLE (-6590 1350);
WIRE 16 -1 (-5300 1450)(-6350 1450);
FORCEPROP 0 LAST SIG_NAME TP_CPU0_RSVD_66
J 0
(-6285 1460);
DISPLAY 0.617021 (-6285 1460);
PAINT ORANGE (-6285 1460);
FORCEPROP 2 LASTPROP $XRERR UNIQUE?
J 0
(-6590 1450);
DISPLAY 0.638298 (-6590 1450);
PAINT MONO (-6590 1450);
DISPLAY INVISIBLE (-6590 1450);
WIRE 16 -1 (-5300 1500)(-6350 1500);
FORCEPROP 0 LAST SIG_NAME TP_CPU0_RSVD_67
J 0
(-6285 1510);
DISPLAY 0.617021 (-6285 1510);
PAINT ORANGE (-6285 1510);
FORCEPROP 2 LASTPROP $XRERR UNIQUE?
J 0
(-6590 1500);
DISPLAY 0.638298 (-6590 1500);
PAINT MONO (-6590 1500);
DISPLAY INVISIBLE (-6590 1500);
WIRE 16 -1 (-5300 1600)(-6350 1600);
FORCEPROP 0 LAST SIG_NAME TP_CPU0_RSVD_69
J 0
(-6285 1610);
DISPLAY 0.617021 (-6285 1610);
PAINT ORANGE (-6285 1610);
FORCEPROP 2 LASTPROP $XRERR UNIQUE?
J 0
(-6590 1600);
DISPLAY 0.638298 (-6590 1600);
PAINT MONO (-6590 1600);
DISPLAY INVISIBLE (-6590 1600);
WIRE 16 -1 (-5300 1650)(-6350 1650);
FORCEPROP 0 LAST SIG_NAME TP_CPU0_RSVD_70
J 0
(-6285 1660);
DISPLAY 0.617021 (-6285 1660);
PAINT ORANGE (-6285 1660);
FORCEPROP 2 LASTPROP $XRERR UNIQUE?
J 0
(-6590 1650);
DISPLAY 0.638298 (-6590 1650);
PAINT MONO (-6590 1650);
DISPLAY INVISIBLE (-6590 1650);
WIRE 16 -1 (-5300 1750)(-6350 1750);
FORCEPROP 0 LAST SIG_NAME TP_CPU0_RSVD_72
J 0
(-6285 1760);
DISPLAY 0.617021 (-6285 1760);
PAINT ORANGE (-6285 1760);
FORCEPROP 2 LASTPROP $XRERR UNIQUE?
J 0
(-6590 1750);
DISPLAY 0.638298 (-6590 1750);
PAINT MONO (-6590 1750);
DISPLAY INVISIBLE (-6590 1750);
WIRE 16 -1 (-5300 1800)(-6350 1800);
FORCEPROP 0 LAST SIG_NAME TP_CPU0_RSVD_73
J 0
(-6285 1810);
DISPLAY 0.617021 (-6285 1810);
PAINT ORANGE (-6285 1810);
FORCEPROP 2 LASTPROP $XRERR UNIQUE?
J 0
(-6590 1800);
DISPLAY 0.638298 (-6590 1800);
PAINT MONO (-6590 1800);
DISPLAY INVISIBLE (-6590 1800);
WIRE 16 -1 (-6350 2150)(-5300 2150);
FORCEPROP 2 LAST SIG_NAME VSENSE_PVCCIOMCP_CPU0_SKT_VRTN
J 0
(-6285 2160);
DISPLAY 0.617021 (-6285 2160);
PAINT ORANGE (-6285 2160);
WIRE 16 -1 (-5300 2200)(-6350 2200);
FORCEPROP 2 LAST SIG_NAME VSENSE_PVCCIOMCP_CPU0_SKT_VSEN
J 0
(-6285 2210);
DISPLAY 0.617021 (-6285 2210);
PAINT ORANGE (-6285 2210);
WIRE 16 -1 (-6350 2300)(-5300 2300);
FORCEPROP 2 LAST SIG_NAME VSENSE_PVCCMCP_CPU0_SKT_VRTN
J 0
(-6285 2310);
DISPLAY 0.617021 (-6285 2310);
PAINT ORANGE (-6285 2310);
WIRE 16 -1 (-6350 2450)(-5300 2450);
FORCEPROP 2 LAST SIG_NAME VSENSE_PVSA_CPU0_SKT_VRTN
J 0
(-6285 2460);
DISPLAY 0.617021 (-6285 2460);
PAINT ORANGE (-6285 2460);
WIRE 16 -1 (-6350 2500)(-5300 2500);
FORCEPROP 2 LAST SIG_NAME VSENSE_PVSA_CPU0_SKT_VSEN
J 0
(-6285 2510);
DISPLAY 0.617021 (-6285 2510);
PAINT ORANGE (-6285 2510);
WIRE 16 -1 (-5300 2650)(-6350 2650);
FORCEPROP 0 LAST SIG_NAME TP_CPU0_KTI2_AMONV
J 0
(-6285 2660);
DISPLAY 0.617021 (-6285 2660);
PAINT ORANGE (-6285 2660);
FORCEPROP 2 LASTPROP $XRERR UNIQUE?
J 0
(-6590 2650);
DISPLAY 0.638298 (-6590 2650);
PAINT MONO (-6590 2650);
DISPLAY INVISIBLE (-6590 2650);
WIRE 16 -1 (-5300 2350)(-6350 2350);
FORCEPROP 2 LAST SIG_NAME VSENSE_PVCCMCP_CPU0_SKT_VSEN
J 0
(-6285 2360);
DISPLAY 0.617021 (-6285 2360);
PAINT ORANGE (-6285 2360);
WIRE 16 -1 (-3200 1600)(-2525 1600);
FORCEPROP 0 LAST SIG_NAME TP_CPU0_RSVD_13
J 0
(-2935 1610);
DISPLAY 0.617021 (-2935 1610);
PAINT ORANGE (-2935 1610);
FORCEPROP 2 LASTPROP $XRERR UNIQUE?
J 0
(-2495 1600);
DISPLAY 0.638298 (-2495 1600);
PAINT MONO (-2495 1600);
DISPLAY INVISIBLE (-2495 1600);
WIRE 16 -1 (-3200 3100)(-2525 3100);
FORCEPROP 0 LAST SIG_NAME TP_CPU0_RSVD_43
J 0
(-2935 3110);
DISPLAY 0.617021 (-2935 3110);
PAINT ORANGE (-2935 3110);
FORCEPROP 2 LASTPROP $XRERR UNIQUE?
J 0
(-2495 3100);
DISPLAY 0.638298 (-2495 3100);
PAINT MONO (-2495 3100);
DISPLAY INVISIBLE (-2495 3100);
WIRE 16 -1 (-3200 950)(-2525 950);
FORCEPROP 0 LAST SIG_NAME TP_CPU0_RSVD_0
J 0
(-2935 960);
DISPLAY 0.617021 (-2935 960);
PAINT ORANGE (-2935 960);
FORCEPROP 2 LASTPROP $XRERR UNIQUE?
J 0
(-2495 950);
DISPLAY 0.638298 (-2495 950);
PAINT MONO (-2495 950);
DISPLAY INVISIBLE (-2495 950);
WIRE 16 -1 (-3200 1000)(-2525 1000);
FORCEPROP 0 LAST SIG_NAME TP_CPU0_RSVD_1
J 0
(-2935 1010);
DISPLAY 0.617021 (-2935 1010);
PAINT ORANGE (-2935 1010);
FORCEPROP 2 LASTPROP $XRERR UNIQUE?
J 0
(-2495 1000);
DISPLAY 0.638298 (-2495 1000);
PAINT MONO (-2495 1000);
DISPLAY INVISIBLE (-2495 1000);
WIRE 16 -1 (-3200 1050)(-2525 1050);
FORCEPROP 0 LAST SIG_NAME TP_CPU0_RSVD_2
J 0
(-2935 1060);
DISPLAY 0.617021 (-2935 1060);
PAINT ORANGE (-2935 1060);
FORCEPROP 2 LASTPROP $XRERR UNIQUE?
J 0
(-2495 1050);
DISPLAY 0.638298 (-2495 1050);
PAINT MONO (-2495 1050);
DISPLAY INVISIBLE (-2495 1050);
WIRE 16 -1 (-3200 1100)(-2525 1100);
FORCEPROP 0 LAST SIG_NAME TP_CPU0_RSVD_3
J 0
(-2935 1110);
DISPLAY 0.617021 (-2935 1110);
PAINT ORANGE (-2935 1110);
FORCEPROP 2 LASTPROP $XRERR UNIQUE?
J 0
(-2495 1100);
DISPLAY 0.638298 (-2495 1100);
PAINT MONO (-2495 1100);
DISPLAY INVISIBLE (-2495 1100);
WIRE 16 -1 (-3200 1150)(-2525 1150);
FORCEPROP 0 LAST SIG_NAME TP_CPU0_RSVD_4
J 0
(-2935 1160);
DISPLAY 0.617021 (-2935 1160);
PAINT ORANGE (-2935 1160);
FORCEPROP 2 LASTPROP $XRERR UNIQUE?
J 0
(-2495 1150);
DISPLAY 0.638298 (-2495 1150);
PAINT MONO (-2495 1150);
DISPLAY INVISIBLE (-2495 1150);
WIRE 16 -1 (-3200 1200)(-2525 1200);
FORCEPROP 0 LAST SIG_NAME TP_CPU0_RSVD_5
J 0
(-2935 1210);
DISPLAY 0.617021 (-2935 1210);
PAINT ORANGE (-2935 1210);
FORCEPROP 2 LASTPROP $XRERR UNIQUE?
J 0
(-2495 1200);
DISPLAY 0.638298 (-2495 1200);
PAINT MONO (-2495 1200);
DISPLAY INVISIBLE (-2495 1200);
WIRE 16 -1 (-3200 1250)(-2525 1250);
FORCEPROP 0 LAST SIG_NAME TP_CPU0_RSVD_6
J 0
(-2935 1260);
DISPLAY 0.617021 (-2935 1260);
PAINT ORANGE (-2935 1260);
FORCEPROP 2 LASTPROP $XRERR UNIQUE?
J 0
(-2495 1250);
DISPLAY 0.638298 (-2495 1250);
PAINT MONO (-2495 1250);
DISPLAY INVISIBLE (-2495 1250);
WIRE 16 -1 (-3200 1300)(-2525 1300);
FORCEPROP 0 LAST SIG_NAME TP_CPU0_RSVD_7
J 0
(-2935 1310);
DISPLAY 0.617021 (-2935 1310);
PAINT ORANGE (-2935 1310);
FORCEPROP 2 LASTPROP $XRERR UNIQUE?
J 0
(-2495 1300);
DISPLAY 0.638298 (-2495 1300);
PAINT MONO (-2495 1300);
DISPLAY INVISIBLE (-2495 1300);
WIRE 16 -1 (-3200 1350)(-2525 1350);
FORCEPROP 0 LAST SIG_NAME TP_CPU0_RSVD_8
J 0
(-2935 1360);
DISPLAY 0.617021 (-2935 1360);
PAINT ORANGE (-2935 1360);
FORCEPROP 2 LASTPROP $XRERR UNIQUE?
J 0
(-2495 1350);
DISPLAY 0.638298 (-2495 1350);
PAINT MONO (-2495 1350);
DISPLAY INVISIBLE (-2495 1350);
WIRE 16 -1 (-3200 1400)(-2525 1400);
FORCEPROP 0 LAST SIG_NAME TP_CPU0_RSVD_9
J 0
(-2935 1410);
DISPLAY 0.617021 (-2935 1410);
PAINT ORANGE (-2935 1410);
FORCEPROP 2 LASTPROP $XRERR UNIQUE?
J 0
(-2495 1400);
DISPLAY 0.638298 (-2495 1400);
PAINT MONO (-2495 1400);
DISPLAY INVISIBLE (-2495 1400);
WIRE 16 -1 (-3200 1450)(-2525 1450);
FORCEPROP 0 LAST SIG_NAME TP_CPU0_RSVD_10
J 0
(-2935 1460);
DISPLAY 0.617021 (-2935 1460);
PAINT ORANGE (-2935 1460);
FORCEPROP 2 LASTPROP $XRERR UNIQUE?
J 0
(-2495 1450);
DISPLAY 0.638298 (-2495 1450);
PAINT MONO (-2495 1450);
DISPLAY INVISIBLE (-2495 1450);
WIRE 16 -1 (-3200 1500)(-2525 1500);
FORCEPROP 0 LAST SIG_NAME TP_CPU0_RSVD_11
J 0
(-2935 1510);
DISPLAY 0.617021 (-2935 1510);
PAINT ORANGE (-2935 1510);
FORCEPROP 2 LASTPROP $XRERR UNIQUE?
J 0
(-2495 1500);
DISPLAY 0.638298 (-2495 1500);
PAINT MONO (-2495 1500);
DISPLAY INVISIBLE (-2495 1500);
WIRE 16 -1 (-3200 1650)(-2525 1650);
FORCEPROP 0 LAST SIG_NAME TP_CPU0_RSVD_14
J 0
(-2935 1660);
DISPLAY 0.617021 (-2935 1660);
PAINT ORANGE (-2935 1660);
FORCEPROP 2 LASTPROP $XRERR UNIQUE?
J 0
(-2495 1650);
DISPLAY 0.638298 (-2495 1650);
PAINT MONO (-2495 1650);
DISPLAY INVISIBLE (-2495 1650);
WIRE 16 -1 (-3200 1700)(-2525 1700);
FORCEPROP 0 LAST SIG_NAME TP_CPU0_RSVD_15
J 0
(-2935 1710);
DISPLAY 0.617021 (-2935 1710);
PAINT ORANGE (-2935 1710);
FORCEPROP 2 LASTPROP $XRERR UNIQUE?
J 0
(-2495 1700);
DISPLAY 0.638298 (-2495 1700);
PAINT MONO (-2495 1700);
DISPLAY INVISIBLE (-2495 1700);
WIRE 16 -1 (-3200 1750)(-2525 1750);
FORCEPROP 0 LAST SIG_NAME TP_CPU0_RSVD_16
J 0
(-2935 1760);
DISPLAY 0.617021 (-2935 1760);
PAINT ORANGE (-2935 1760);
FORCEPROP 2 LASTPROP $XRERR UNIQUE?
J 0
(-2495 1750);
DISPLAY 0.638298 (-2495 1750);
PAINT MONO (-2495 1750);
DISPLAY INVISIBLE (-2495 1750);
WIRE 16 -1 (-3200 1800)(-2525 1800);
FORCEPROP 0 LAST SIG_NAME TP_CPU0_RSVD_17
J 0
(-2935 1810);
DISPLAY 0.617021 (-2935 1810);
PAINT ORANGE (-2935 1810);
FORCEPROP 2 LASTPROP $XRERR UNIQUE?
J 0
(-2495 1800);
DISPLAY 0.638298 (-2495 1800);
PAINT MONO (-2495 1800);
DISPLAY INVISIBLE (-2495 1800);
WIRE 16 -1 (-3200 1850)(-2525 1850);
FORCEPROP 0 LAST SIG_NAME TP_CPU0_RSVD_18
J 0
(-2935 1860);
DISPLAY 0.617021 (-2935 1860);
PAINT ORANGE (-2935 1860);
FORCEPROP 2 LASTPROP $XRERR UNIQUE?
J 0
(-2495 1850);
DISPLAY 0.638298 (-2495 1850);
PAINT MONO (-2495 1850);
DISPLAY INVISIBLE (-2495 1850);
WIRE 16 -1 (-3200 1900)(-2525 1900);
FORCEPROP 0 LAST SIG_NAME TP_CPU0_RSVD_19
J 0
(-2935 1910);
DISPLAY 0.617021 (-2935 1910);
PAINT ORANGE (-2935 1910);
FORCEPROP 2 LASTPROP $XRERR UNIQUE?
J 0
(-2495 1900);
DISPLAY 0.638298 (-2495 1900);
PAINT MONO (-2495 1900);
DISPLAY INVISIBLE (-2495 1900);
WIRE 16 -1 (-3200 1950)(-2525 1950);
FORCEPROP 0 LAST SIG_NAME TP_CPU0_RSVD_20
J 0
(-2935 1960);
DISPLAY 0.617021 (-2935 1960);
PAINT ORANGE (-2935 1960);
FORCEPROP 2 LASTPROP $XRERR UNIQUE?
J 0
(-2495 1950);
DISPLAY 0.638298 (-2495 1950);
PAINT MONO (-2495 1950);
DISPLAY INVISIBLE (-2495 1950);
WIRE 16 -1 (-3200 2000)(-2525 2000);
FORCEPROP 0 LAST SIG_NAME TP_CPU0_RSVD_21
J 0
(-2935 2010);
DISPLAY 0.617021 (-2935 2010);
PAINT ORANGE (-2935 2010);
FORCEPROP 2 LASTPROP $XRERR UNIQUE?
J 0
(-2495 2000);
DISPLAY 0.638298 (-2495 2000);
PAINT MONO (-2495 2000);
DISPLAY INVISIBLE (-2495 2000);
WIRE 16 -1 (-3200 2050)(-2525 2050);
FORCEPROP 0 LAST SIG_NAME TP_CPU0_RSVD_22
J 0
(-2935 2060);
DISPLAY 0.617021 (-2935 2060);
PAINT ORANGE (-2935 2060);
FORCEPROP 2 LASTPROP $XRERR UNIQUE?
J 0
(-2495 2050);
DISPLAY 0.638298 (-2495 2050);
PAINT MONO (-2495 2050);
DISPLAY INVISIBLE (-2495 2050);
WIRE 16 -1 (-3200 2100)(-2525 2100);
FORCEPROP 0 LAST SIG_NAME TP_CPU0_RSVD_23
J 0
(-2935 2110);
DISPLAY 0.617021 (-2935 2110);
PAINT ORANGE (-2935 2110);
FORCEPROP 2 LASTPROP $XRERR UNIQUE?
J 0
(-2495 2100);
DISPLAY 0.638298 (-2495 2100);
PAINT MONO (-2495 2100);
DISPLAY INVISIBLE (-2495 2100);
WIRE 16 -1 (-3200 2150)(-2525 2150);
FORCEPROP 0 LAST SIG_NAME TP_CPU0_RSVD_24
J 0
(-2935 2160);
DISPLAY 0.617021 (-2935 2160);
PAINT ORANGE (-2935 2160);
FORCEPROP 2 LASTPROP $XRERR UNIQUE?
J 0
(-2495 2150);
DISPLAY 0.638298 (-2495 2150);
PAINT MONO (-2495 2150);
DISPLAY INVISIBLE (-2495 2150);
WIRE 16 -1 (-3200 2200)(-2525 2200);
FORCEPROP 0 LAST SIG_NAME TP_CPU0_RSVD_25
J 0
(-2935 2210);
DISPLAY 0.617021 (-2935 2210);
PAINT ORANGE (-2935 2210);
FORCEPROP 2 LASTPROP $XRERR UNIQUE?
J 0
(-2495 2200);
DISPLAY 0.638298 (-2495 2200);
PAINT MONO (-2495 2200);
DISPLAY INVISIBLE (-2495 2200);
WIRE 16 -1 (-3200 2250)(-2525 2250);
FORCEPROP 0 LAST SIG_NAME TP_CPU0_RSVD_26
J 0
(-2935 2260);
DISPLAY 0.617021 (-2935 2260);
PAINT ORANGE (-2935 2260);
FORCEPROP 2 LASTPROP $XRERR UNIQUE?
J 0
(-2495 2250);
DISPLAY 0.638298 (-2495 2250);
PAINT MONO (-2495 2250);
DISPLAY INVISIBLE (-2495 2250);
WIRE 16 -1 (-3200 2300)(-2525 2300);
FORCEPROP 0 LAST SIG_NAME TP_CPU0_RSVD_27
J 0
(-2935 2310);
DISPLAY 0.617021 (-2935 2310);
PAINT ORANGE (-2935 2310);
FORCEPROP 2 LASTPROP $XRERR UNIQUE?
J 0
(-2495 2300);
DISPLAY 0.638298 (-2495 2300);
PAINT MONO (-2495 2300);
DISPLAY INVISIBLE (-2495 2300);
WIRE 16 -1 (-3200 2350)(-2525 2350);
FORCEPROP 0 LAST SIG_NAME TP_CPU0_RSVD_28
J 0
(-2935 2360);
DISPLAY 0.617021 (-2935 2360);
PAINT ORANGE (-2935 2360);
FORCEPROP 2 LASTPROP $XRERR UNIQUE?
J 0
(-2495 2350);
DISPLAY 0.638298 (-2495 2350);
PAINT MONO (-2495 2350);
DISPLAY INVISIBLE (-2495 2350);
WIRE 16 -1 (-3200 2400)(-2525 2400);
FORCEPROP 0 LAST SIG_NAME TP_CPU0_RSVD_29
J 0
(-2935 2410);
DISPLAY 0.617021 (-2935 2410);
PAINT ORANGE (-2935 2410);
FORCEPROP 2 LASTPROP $XRERR UNIQUE?
J 0
(-2495 2400);
DISPLAY 0.638298 (-2495 2400);
PAINT MONO (-2495 2400);
DISPLAY INVISIBLE (-2495 2400);
WIRE 16 -1 (-3200 2450)(-2525 2450);
FORCEPROP 0 LAST SIG_NAME TP_CPU0_RSVD_30
J 0
(-2935 2460);
DISPLAY 0.617021 (-2935 2460);
PAINT ORANGE (-2935 2460);
FORCEPROP 2 LASTPROP $XRERR UNIQUE?
J 0
(-2495 2450);
DISPLAY 0.638298 (-2495 2450);
PAINT MONO (-2495 2450);
DISPLAY INVISIBLE (-2495 2450);
WIRE 16 -1 (-3200 2500)(-2525 2500);
FORCEPROP 0 LAST SIG_NAME TP_CPU0_RSVD_31
J 0
(-2935 2510);
DISPLAY 0.617021 (-2935 2510);
PAINT ORANGE (-2935 2510);
FORCEPROP 2 LASTPROP $XRERR UNIQUE?
J 0
(-2495 2500);
DISPLAY 0.638298 (-2495 2500);
PAINT MONO (-2495 2500);
DISPLAY INVISIBLE (-2495 2500);
WIRE 16 -1 (-3200 2700)(-2525 2700);
FORCEPROP 0 LAST SIG_NAME TP_CPU0_RSVD_35
J 0
(-2935 2710);
DISPLAY 0.617021 (-2935 2710);
PAINT ORANGE (-2935 2710);
FORCEPROP 2 LASTPROP $XRERR UNIQUE?
J 0
(-2495 2700);
DISPLAY 0.638298 (-2495 2700);
PAINT MONO (-2495 2700);
DISPLAY INVISIBLE (-2495 2700);
WIRE 16 -1 (-3200 2750)(-2525 2750);
FORCEPROP 0 LAST SIG_NAME TP_CPU0_RSVD_36
J 0
(-2935 2760);
DISPLAY 0.617021 (-2935 2760);
PAINT ORANGE (-2935 2760);
FORCEPROP 2 LASTPROP $XRERR UNIQUE?
J 0
(-2495 2750);
DISPLAY 0.638298 (-2495 2750);
PAINT MONO (-2495 2750);
DISPLAY INVISIBLE (-2495 2750);
WIRE 16 -1 (-3200 2800)(-2525 2800);
FORCEPROP 0 LAST SIG_NAME TP_CPU0_RSVD_37
J 0
(-2935 2810);
DISPLAY 0.617021 (-2935 2810);
PAINT ORANGE (-2935 2810);
FORCEPROP 2 LASTPROP $XRERR UNIQUE?
J 0
(-2495 2800);
DISPLAY 0.638298 (-2495 2800);
PAINT MONO (-2495 2800);
DISPLAY INVISIBLE (-2495 2800);
WIRE 16 -1 (-3200 2850)(-2525 2850);
FORCEPROP 0 LAST SIG_NAME TP_CPU0_RSVD_38
J 0
(-2935 2860);
DISPLAY 0.617021 (-2935 2860);
PAINT ORANGE (-2935 2860);
FORCEPROP 2 LASTPROP $XRERR UNIQUE?
J 0
(-2495 2850);
DISPLAY 0.638298 (-2495 2850);
PAINT MONO (-2495 2850);
DISPLAY INVISIBLE (-2495 2850);
WIRE 16 -1 (-3200 2900)(-2525 2900);
FORCEPROP 0 LAST SIG_NAME TP_CPU0_RSVD_39
J 0
(-2935 2910);
DISPLAY 0.617021 (-2935 2910);
PAINT ORANGE (-2935 2910);
FORCEPROP 2 LASTPROP $XRERR UNIQUE?
J 0
(-2495 2900);
DISPLAY 0.638298 (-2495 2900);
PAINT MONO (-2495 2900);
DISPLAY INVISIBLE (-2495 2900);
WIRE 16 -1 (-3200 2950)(-2525 2950);
FORCEPROP 0 LAST SIG_NAME TP_CPU0_RSVD_40
J 0
(-2935 2960);
DISPLAY 0.617021 (-2935 2960);
PAINT ORANGE (-2935 2960);
FORCEPROP 2 LASTPROP $XRERR UNIQUE?
J 0
(-2495 2950);
DISPLAY 0.638298 (-2495 2950);
PAINT MONO (-2495 2950);
DISPLAY INVISIBLE (-2495 2950);
WIRE 16 -1 (-3200 3000)(-2525 3000);
FORCEPROP 0 LAST SIG_NAME TP_CPU0_RSVD_41
J 0
(-2935 3010);
DISPLAY 0.617021 (-2935 3010);
PAINT ORANGE (-2935 3010);
FORCEPROP 2 LASTPROP $XRERR UNIQUE?
J 0
(-2495 3000);
DISPLAY 0.638298 (-2495 3000);
PAINT MONO (-2495 3000);
DISPLAY INVISIBLE (-2495 3000);
WIRE 16 -1 (-3200 3050)(-2525 3050);
FORCEPROP 0 LAST SIG_NAME TP_CPU0_RSVD_42
J 0
(-2935 3060);
DISPLAY 0.617021 (-2935 3060);
PAINT ORANGE (-2935 3060);
FORCEPROP 2 LASTPROP $XRERR UNIQUE?
J 0
(-2495 3050);
DISPLAY 0.638298 (-2495 3050);
PAINT MONO (-2495 3050);
DISPLAY INVISIBLE (-2495 3050);
WIRE 16 -1 (-3200 3150)(-2525 3150);
FORCEPROP 0 LAST SIG_NAME TP_CPU0_RSVD_44
J 0
(-2935 3160);
DISPLAY 0.617021 (-2935 3160);
PAINT ORANGE (-2935 3160);
FORCEPROP 2 LASTPROP $XRERR UNIQUE?
J 0
(-2495 3150);
DISPLAY 0.638298 (-2495 3150);
PAINT MONO (-2495 3150);
DISPLAY INVISIBLE (-2495 3150);
WIRE 16 -1 (-3200 3200)(-2525 3200);
FORCEPROP 0 LAST SIG_NAME TP_CPU0_RSVD_45
J 0
(-2935 3210);
DISPLAY 0.617021 (-2935 3210);
PAINT ORANGE (-2935 3210);
FORCEPROP 2 LASTPROP $XRERR UNIQUE?
J 0
(-2495 3200);
DISPLAY 0.638298 (-2495 3200);
PAINT MONO (-2495 3200);
DISPLAY INVISIBLE (-2495 3200);
WIRE 16 -1 (-3200 3250)(-2525 3250);
FORCEPROP 0 LAST SIG_NAME TP_CPU0_RSVD_46
J 0
(-2935 3260);
DISPLAY 0.617021 (-2935 3260);
PAINT ORANGE (-2935 3260);
FORCEPROP 2 LASTPROP $XRERR UNIQUE?
J 0
(-2495 3250);
DISPLAY 0.638298 (-2495 3250);
PAINT MONO (-2495 3250);
DISPLAY INVISIBLE (-2495 3250);
WIRE 16 -1 (-3200 3300)(-2525 3300);
FORCEPROP 0 LAST SIG_NAME TP_CPU0_RSVD_47
J 0
(-2935 3310);
DISPLAY 0.617021 (-2935 3310);
PAINT ORANGE (-2935 3310);
FORCEPROP 2 LASTPROP $XRERR UNIQUE?
J 0
(-2495 3300);
DISPLAY 0.638298 (-2495 3300);
PAINT MONO (-2495 3300);
DISPLAY INVISIBLE (-2495 3300);
WIRE 16 -1 (-3200 3350)(-2525 3350);
FORCEPROP 0 LAST SIG_NAME TP_CPU0_RSVD_48
J 0
(-2935 3360);
DISPLAY 0.617021 (-2935 3360);
PAINT ORANGE (-2935 3360);
FORCEPROP 2 LASTPROP $XRERR UNIQUE?
J 0
(-2495 3350);
DISPLAY 0.638298 (-2495 3350);
PAINT MONO (-2495 3350);
DISPLAY INVISIBLE (-2495 3350);
WIRE 16 -1 (-3200 3400)(-2525 3400);
FORCEPROP 0 LAST SIG_NAME TP_CPU0_RSVD_49
J 0
(-2935 3410);
DISPLAY 0.617021 (-2935 3410);
PAINT ORANGE (-2935 3410);
FORCEPROP 2 LASTPROP $XRERR UNIQUE?
J 0
(-2495 3400);
DISPLAY 0.638298 (-2495 3400);
PAINT MONO (-2495 3400);
DISPLAY INVISIBLE (-2495 3400);
WIRE 16 -1 (-3200 3450)(-2525 3450);
FORCEPROP 0 LAST SIG_NAME TP_CPU0_RSVD_50
J 0
(-2935 3460);
DISPLAY 0.617021 (-2935 3460);
PAINT ORANGE (-2935 3460);
FORCEPROP 2 LASTPROP $XRERR UNIQUE?
J 0
(-2495 3450);
DISPLAY 0.638298 (-2495 3450);
PAINT MONO (-2495 3450);
DISPLAY INVISIBLE (-2495 3450);
WIRE 16 -1 (-3200 3500)(-2525 3500);
FORCEPROP 0 LAST SIG_NAME TP_CPU0_RSVD_51
J 0
(-2935 3510);
DISPLAY 0.617021 (-2935 3510);
PAINT ORANGE (-2935 3510);
FORCEPROP 2 LASTPROP $XRERR UNIQUE?
J 0
(-2495 3500);
DISPLAY 0.638298 (-2495 3500);
PAINT MONO (-2495 3500);
DISPLAY INVISIBLE (-2495 3500);
WIRE 16 -1 (-3200 3600)(-2525 3600);
FORCEPROP 0 LAST SIG_NAME TP_CPU0_RSVD_53
J 0
(-2935 3610);
DISPLAY 0.617021 (-2935 3610);
PAINT ORANGE (-2935 3610);
FORCEPROP 2 LASTPROP $XRERR UNIQUE?
J 0
(-2495 3600);
DISPLAY 0.638298 (-2495 3600);
PAINT MONO (-2495 3600);
DISPLAY INVISIBLE (-2495 3600);
WIRE 16 -1 (-3200 3650)(-2525 3650);
FORCEPROP 0 LAST SIG_NAME TP_CPU0_RSVD_54
J 0
(-2935 3660);
DISPLAY 0.617021 (-2935 3660);
PAINT ORANGE (-2935 3660);
FORCEPROP 2 LASTPROP $XRERR UNIQUE?
J 0
(-2495 3650);
DISPLAY 0.638298 (-2495 3650);
PAINT MONO (-2495 3650);
DISPLAY INVISIBLE (-2495 3650);
WIRE 16 -1 (-3200 3700)(-2525 3700);
FORCEPROP 0 LAST SIG_NAME TP_CPU0_RSVD_55
J 0
(-2935 3710);
DISPLAY 0.617021 (-2935 3710);
PAINT ORANGE (-2935 3710);
FORCEPROP 2 LASTPROP $XRERR UNIQUE?
J 0
(-2495 3700);
DISPLAY 0.638298 (-2495 3700);
PAINT MONO (-2495 3700);
DISPLAY INVISIBLE (-2495 3700);
WIRE 16 -1 (-3200 3750)(-2525 3750);
FORCEPROP 0 LAST SIG_NAME TP_CPU0_RSVD_56
J 0
(-2935 3760);
DISPLAY 0.617021 (-2935 3760);
PAINT ORANGE (-2935 3760);
FORCEPROP 2 LASTPROP $XRERR UNIQUE?
J 0
(-2495 3750);
DISPLAY 0.638298 (-2495 3750);
PAINT MONO (-2495 3750);
DISPLAY INVISIBLE (-2495 3750);
WIRE 16 -1 (-3200 3800)(-2525 3800);
FORCEPROP 0 LAST SIG_NAME TP_CPU0_RSVD_57
J 0
(-2935 3810);
DISPLAY 0.617021 (-2935 3810);
PAINT ORANGE (-2935 3810);
FORCEPROP 2 LASTPROP $XRERR UNIQUE?
J 0
(-2495 3800);
DISPLAY 0.638298 (-2495 3800);
PAINT MONO (-2495 3800);
DISPLAY INVISIBLE (-2495 3800);
WIRE 16 -1 (-3200 3900)(-2525 3900);
FORCEPROP 0 LAST SIG_NAME TP_CPU0_RSVD_59
J 0
(-2935 3910);
DISPLAY 0.617021 (-2935 3910);
PAINT ORANGE (-2935 3910);
FORCEPROP 2 LASTPROP $XRERR UNIQUE?
J 0
(-2495 3900);
DISPLAY 0.638298 (-2495 3900);
PAINT MONO (-2495 3900);
DISPLAY INVISIBLE (-2495 3900);
WIRE 16 -1 (-3200 3950)(-2525 3950);
FORCEPROP 0 LAST SIG_NAME TP_CPU0_RSVD_60
J 0
(-2935 3960);
DISPLAY 0.617021 (-2935 3960);
PAINT ORANGE (-2935 3960);
FORCEPROP 2 LASTPROP $XRERR UNIQUE?
J 0
(-2495 3950);
DISPLAY 0.638298 (-2495 3950);
PAINT MONO (-2495 3950);
DISPLAY INVISIBLE (-2495 3950);
DOT 1 (-5650 3950);
DOT 1 (-5650 3900);
DOT 1 (-5650 3800);
DOT 1 (-5650 2950);
DOT 1 (-5475 2700);
DOT 1 (-5475 1400);
DOT 1 (-5475 2750);
DOT 1 (-5650 3450);
DOT 1 (-5650 3100);
DOT 1 (-5650 3300);
DOT 1 (-5650 3750);
DOT 1 (-5650 3600);
DOT 1 (-5650 3250);
DOT 1 (-5650 3200);
DOT 1 (-5650 3150);
DOT 1 (-5650 3050);
DOT 1 (-5650 3000);
DOT 1 (-5650 3350);
DOT 1 (-5650 3650);
DOT 1 (-5650 3700);
DOT 1 (-5650 3550);
DOT 1 (-5650 3500);
DOT 1 (-2250 3850);
DOT 1 (-5475 1850);
DOT 1 (-5475 1550);
DOT 1 (-5475 1700);
DOT 1 (-5475 2600);
FORCENOTE
ROOM=CPU0
(-7925 325) 0;
DISPLAY LEFT (-7925 325);
DISPLAY 1.723404 (-7925 325);
PAINT PURPLE (-7925 325);
FORCENOTE
BOM_COST=PROC_SOCKET
(-7925 200) 0;
DISPLAY LEFT (-7925 200);
DISPLAY 1.723404 (-7925 200);
PAINT PURPLE (-7925 200);
FORCENOTE
SKYLAKE - SKT0 - 19 OF 21
(-1675 150) 0;
DISPLAY LEFT (-1675 150);
DISPLAY 1.021277 (-1675 150);
PAINT RED (-1675 150);
QUIT
